# T6G (Grand Teton) — schematic netlist excerpt (pin names and nets, part order shuffled) for the footprints in the layout excerpt that follows; sources: Cadence DE-HDL packaged netlist, KiCad conversion of 04192023_DAF0TMB3IC0_F0TG_MB_C_brd_V02_OCP.brd

R3069  Q_RES  130 1% CHIP  pkg 0402LF  page 254 : A = LED_PWRGD_SYS_PWROK_R ; B = P3V3_AUX
C663  Q_CAP  22UF 4V 20% X6S  pkg C0402  page 290 : A = P0V9_CPU0_RT1_2A ; B = GND

(kicad_pcb
	(version 20260206)
	(generator "pcbnew")
	(generator_version "10.0")
	(general
		(thickness 1.6)
		(legacy_teardrops no)
	)
	(paper "A4")
	(title_block
		(title "04192023_DAF0TMB3IC0_F0TG_MB_C_brd_V02_OCP.brd")
		(comment 1 "Grand Teton / footprints 6993-6994 of 8354")
	)
	(layers
		(0 "F.Cu" signal "TOP")
		(4 "In1.Cu" signal "GND")
		(6 "In2.Cu" signal "IN1")
		(8 "In3.Cu" signal "GND1")
		(10 "In4.Cu" signal "IN2")
		(12 "In5.Cu" signal "GND2")
		(14 "In6.Cu" signal "IN3")
		(16 "In7.Cu" signal "GND3")
		(18 "In8.Cu" signal "VCC")
		(20 "In9.Cu" signal "VCC1")
		(22 "In10.Cu" signal "GND4")
		(24 "In11.Cu" signal "IN4")
		(26 "In12.Cu" signal "GND5")
		(28 "In13.Cu" signal "IN5")
		(30 "In14.Cu" signal "GND6")
		(32 "In15.Cu" signal "IN6")
		(34 "In16.Cu" signal "GND7")
		(2 "B.Cu" signal "BOTTOM")
		(9 "F.Adhes" user "F.Adhesive")
		(11 "B.Adhes" user "B.Adhesive")
		(13 "F.Paste" user "Package Geometry/Pastemask Top")
		(15 "B.Paste" user "Package Geometry/Pastemask Bottom")
		(5 "F.SilkS" user "Ref Des/Silkscreen Top")
		(7 "B.SilkS" user "Ref Des/Silkscreen Bottom")
		(1 "F.Mask" user "Board Geometry/Soldermask Top")
		(3 "B.Mask" user "Board Geometry/Soldermask Bottom")
		(17 "Dwgs.User" user "User.Drawings")
		(19 "Cmts.User" user "User.Comments")
		(21 "Eco1.User" user "User.Eco1")
		(23 "Eco2.User" user "User.Eco2")
		(25 "Edge.Cuts" user "Board Geometry/Outline")
		(27 "Margin" user)
		(31 "F.CrtYd" user "Package Geometry/Place Bound Top")
		(29 "B.CrtYd" user "Package Geometry/Place Bound Bottom")
		(35 "F.Fab" user "Ref Des/Assembly Top")
		(33 "B.Fab" user "Ref Des/Assembly Bottom")
	)
	(footprint ""
		(layer "B.Cu")
		(at 312.443876 -66.708782 90)
		(property "Reference" "R3069"
			(at 0 0 90)
			(layer "B.SilkS")
			(hide yes)
			(effects
				(font
					(size 1.27 1.27)
				)
				(justify mirror)
			)
		)
		(property "Value" ""
			(at 0 0 90)
			(layer "B.Fab")
			(effects
				(font
					(size 1.27 1.27)
				)
				(justify mirror)
			)
		)
		(duplicate_pad_numbers_are_jumpers no)
		(fp_line
			(start 0.7874 -0.4064)
			(end -0.7874 -0.4064)
			(stroke
				(width 0.1524)
				(type default)
			)
			(layer "B.SilkS")
		)
		(fp_line
			(start -0.7874 -0.4064)
			(end -0.7874 0.4064)
			(stroke
				(width 0.1524)
				(type default)
			)
			(layer "B.SilkS")
		)
		(fp_line
			(start 0.7874 0.4064)
			(end 0.7874 -0.4064)
			(stroke
				(width 0.1524)
				(type default)
			)
			(layer "B.SilkS")
		)
		(fp_line
			(start -0.7874 0.4064)
			(end 0.7874 0.4064)
			(stroke
				(width 0.1524)
				(type default)
			)
			(layer "B.SilkS")
		)
		(fp_line
			(start 0.67945 -0.305054)
			(end 0.12065 -0.305054)
			(stroke
				(width 0.1)
				(type default)
			)
			(layer "B.Fab")
		)
		(fp_line
			(start 0.12065 -0.305054)
			(end 0.12065 -0.2794)
			(stroke
				(width 0.1)
				(type default)
			)
			(layer "B.Fab")
		)
		(fp_line
			(start -0.12065 -0.3048)
			(end -0.67945 -0.3048)
			(stroke
				(width 0.1)
				(type default)
			)
			(layer "B.Fab")
		)
		(fp_line
			(start -0.67945 -0.3048)
			(end -0.67945 0.3048)
			(stroke
				(width 0.1)
				(type default)
			)
			(layer "B.Fab")
		)
		(fp_line
			(start 0.12065 -0.2794)
			(end -0.12065 -0.2794)
			(stroke
				(width 0.1)
				(type default)
			)
			(layer "B.Fab")
		)
		(fp_line
			(start -0.12065 -0.2794)
			(end -0.12065 -0.3048)
			(stroke
				(width 0.1)
				(type default)
			)
			(layer "B.Fab")
		)
		(fp_line
			(start 0.12065 0.2794)
			(end 0.12065 0.3048)
			(stroke
				(width 0.1)
				(type default)
			)
			(layer "B.Fab")
		)
		(fp_line
			(start -0.120396 0.2794)
			(end 0.12065 0.2794)
			(stroke
				(width 0.1)
				(type default)
			)
			(layer "B.Fab")
		)
		(fp_line
			(start 0.67945 0.3048)
			(end 0.67945 -0.305054)
			(stroke
				(width 0.1)
				(type default)
			)
			(layer "B.Fab")
		)
		(fp_line
			(start 0.12065 0.3048)
			(end 0.67945 0.3048)
			(stroke
				(width 0.1)
				(type default)
			)
			(layer "B.Fab")
		)
		(fp_line
			(start -0.120396 0.3048)
			(end -0.120396 0.2794)
			(stroke
				(width 0.1)
				(type default)
			)
			(layer "B.Fab")
		)
		(fp_line
			(start -0.67945 0.3048)
			(end -0.120396 0.3048)
			(stroke
				(width 0.1)
				(type default)
			)
			(layer "B.Fab")
		)
		(pad "1" smd circle
			(at 0.40005 0 270)
			(size 0 0)
			(layers "B.Cu" "B.Mask" "B.Paste")
			(net "LED_PWRGD_SYS_PWROK_R")
		)
		(pad "2" smd circle
			(at -0.40005 0 270)
			(size 0 0)
			(layers "B.Cu" "B.Mask" "B.Paste")
			(net "P3V3_AUX")
		)
	)
	(footprint ""
		(layer "B.Cu")
		(at 355.272848 -398.942052 90)
		(property "Reference" "C663"
			(at 0 0 90)
			(layer "B.SilkS")
			(hide yes)
			(effects
				(font
					(size 1.27 1.27)
				)
				(justify mirror)
			)
		)
		(property "Value" ""
			(at 0 0 90)
			(layer "B.Fab")
			(effects
				(font
					(size 1.27 1.27)
				)
				(justify mirror)
			)
		)
		(duplicate_pad_numbers_are_jumpers no)
		(fp_line
			(start 0.7874 -0.4064)
			(end -0.7874 -0.4064)
			(stroke
				(width 0.1524)
				(type default)
			)
			(layer "B.SilkS")
		)
		(fp_line
			(start -0.7874 -0.4064)
			(end -0.7874 0.4064)
			(stroke
				(width 0.1524)
				(type default)
			)
			(layer "B.SilkS")
		)
		(fp_line
			(start 0.7874 0.4064)
			(end 0.7874 -0.4064)
			(stroke
				(width 0.1524)
				(type default)
			)
			(layer "B.SilkS")
		)
		(fp_line
			(start -0.7874 0.4064)
			(end 0.7874 0.4064)
			(stroke
				(width 0.1524)
				(type default)
			)
			(layer "B.SilkS")
		)
		(fp_line
			(start 0.67945 -0.305054)
			(end 0.12065 -0.305054)
			(stroke
				(width 0.1)
				(type default)
			)
			(layer "B.Fab")
		)
		(fp_line
			(start 0.12065 -0.305054)
			(end 0.12065 -0.2794)
			(stroke
				(width 0.1)
				(type default)
			)
			(layer "B.Fab")
		)
		(fp_line
			(start -0.12065 -0.3048)
			(end -0.67945 -0.3048)
			(stroke
				(width 0.1)
				(type default)
			)
			(layer "B.Fab")
		)
		(fp_line
			(start -0.67945 -0.3048)
			(end -0.67945 0.3048)
			(stroke
				(width 0.1)
				(type default)
			)
			(layer "B.Fab")
		)
		(fp_line
			(start 0.12065 -0.2794)
			(end -0.12065 -0.2794)
			(stroke
				(width 0.1)
				(type default)
			)
			(layer "B.Fab")
		)
		(fp_line
			(start -0.12065 -0.2794)
			(end -0.12065 -0.3048)
			(stroke
				(width 0.1)
				(type default)
			)
			(layer "B.Fab")
		)
		(fp_line
			(start 0.12065 0.2794)
			(end 0.12065 0.3048)
			(stroke
				(width 0.1)
				(type default)
			)
			(layer "B.Fab")
		)
		(fp_line
			(start -0.120396 0.2794)
			(end 0.12065 0.2794)
			(stroke
				(width 0.1)
				(type default)
			)
			(layer "B.Fab")
		)
		(fp_line
			(start 0.67945 0.3048)
			(end 0.67945 -0.305054)
			(stroke
				(width 0.1)
				(type default)
			)
			(layer "B.Fab")
		)
		(fp_line
			(start 0.12065 0.3048)
			(end 0.67945 0.3048)
			(stroke
				(width 0.1)
				(type default)
			)
			(layer "B.Fab")
		)
		(fp_line
			(start -0.120396 0.3048)
			(end -0.120396 0.2794)
			(stroke
				(width 0.1)
				(type default)
			)
			(layer "B.Fab")
		)
		(fp_line
			(start -0.67945 0.3048)
			(end -0.120396 0.3048)
			(stroke
				(width 0.1)
				(type default)
			)
			(layer "B.Fab")
		)
		(pad "1" smd circle
			(at 0.40005 0 270)
			(size 0 0)
			(layers "B.Cu" "B.Mask" "B.Paste")
			(net "P0V9_CPU0_RT1_2A")
		)
		(pad "2" smd circle
			(at -0.40005 0 270)
			(size 0 0)
			(layers "B.Cu" "B.Mask" "B.Paste")
			(net "GND")
		)
	)
)
